(kicad_pcb
	(version 20260206)
	(generator "pcbnew")
	(generator_version "10.0")
	(general
		(thickness 1.6)
		(legacy_teardrops no)
	)
	(paper "A4")
	(title_block
		(title "03242023_DA0F0TMBIJ0_F0T_Motherboard_J_brd_V01_OCP.brd")
		(comment 1 "Grand Teton / footprints 4223-4228 of 6105")
	)
	(layers
		(0 "F.Cu" signal "TOP")
		(4 "In1.Cu" signal "GND")
		(6 "In2.Cu" signal "IN1")
		(8 "In3.Cu" signal "GND1")
		(10 "In4.Cu" signal "IN2")
		(12 "In5.Cu" signal "GND2")
		(14 "In6.Cu" signal "IN3")
		(16 "In7.Cu" signal "GND3")
		(18 "In8.Cu" signal "VCC")
		(20 "In9.Cu" signal "VCC1")
		(22 "In10.Cu" signal "GND4")
		(24 "In11.Cu" signal "IN4")
		(26 "In12.Cu" signal "GND5")
		(28 "In13.Cu" signal "IN5")
		(30 "In14.Cu" signal "GND6")
		(32 "In15.Cu" signal "IN6")
		(34 "In16.Cu" signal "GND7")
		(2 "B.Cu" signal "BOTTOM")
		(9 "F.Adhes" user "F.Adhesive")
		(11 "B.Adhes" user "B.Adhesive")
		(13 "F.Paste" user "Package Geometry/Pastemask Top")
		(15 "B.Paste" user "Package Geometry/Pastemask Bottom")
		(5 "F.SilkS" user "Ref Des/Silkscreen Top")
		(7 "B.SilkS" user "Ref Des/Silkscreen Bottom")
		(1 "F.Mask" user "Board Geometry/Soldermask Top")
		(3 "B.Mask" user "Board Geometry/Soldermask Bottom")
		(17 "Dwgs.User" user "User.Drawings")
		(19 "Cmts.User" user "User.Comments")
		(21 "Eco1.User" user "User.Eco1")
		(23 "Eco2.User" user "User.Eco2")
		(25 "Edge.Cuts" user "Board Geometry/Outline")
		(27 "Margin" user)
		(31 "F.CrtYd" user "Package Geometry/Place Bound Top")
		(29 "B.CrtYd" user "Package Geometry/Place Bound Bottom")
		(35 "F.Fab" user "Ref Des/Assembly Top")
		(33 "B.Fab" user "Ref Des/Assembly Bottom")
	)
	(footprint ""
		(layer "B.Cu")
		(at 175.9712 -319.293748)
		(property "Reference" "R76"
			(at 0 0 0)
			(layer "B.SilkS")
			(hide yes)
			(effects
				(font
					(size 1.27 1.27)
				)
				(justify mirror)
			)
		)
		(property "Value" ""
			(at 0 0 0)
			(layer "B.Fab")
			(effects
				(font
					(size 1.27 1.27)
				)
				(justify mirror)
			)
		)
		(duplicate_pad_numbers_are_jumpers no)
		(fp_line
			(start -0.7874 -0.4064)
			(end -0.7874 0.4064)
			(stroke
				(width 0.1524)
				(type default)
			)
			(layer "B.SilkS")
		)
		(fp_line
			(start -0.7874 0.4064)
			(end 0.7874 0.4064)
			(stroke
				(width 0.1524)
				(type default)
			)
			(layer "B.SilkS")
		)
		(fp_line
			(start 0.7874 -0.4064)
			(end -0.7874 -0.4064)
			(stroke
				(width 0.1524)
				(type default)
			)
			(layer "B.SilkS")
		)
		(fp_line
			(start 0.7874 0.4064)
			(end 0.7874 -0.4064)
			(stroke
				(width 0.1524)
				(type default)
			)
			(layer "B.SilkS")
		)
		(fp_line
			(start -0.67945 -0.3048)
			(end -0.67945 0.3048)
			(stroke
				(width 0.1)
				(type default)
			)
			(layer "B.Fab")
		)
		(fp_line
			(start -0.67945 0.3048)
			(end -0.120396 0.3048)
			(stroke
				(width 0.1)
				(type default)
			)
			(layer "B.Fab")
		)
		(fp_line
			(start -0.12065 -0.3048)
			(end -0.67945 -0.3048)
			(stroke
				(width 0.1)
				(type default)
			)
			(layer "B.Fab")
		)
		(fp_line
			(start -0.12065 -0.2794)
			(end -0.12065 -0.3048)
			(stroke
				(width 0.1)
				(type default)
			)
			(layer "B.Fab")
		)
		(fp_line
			(start -0.120396 0.2794)
			(end 0.12065 0.2794)
			(stroke
				(width 0.1)
				(type default)
			)
			(layer "B.Fab")
		)
		(fp_line
			(start -0.120396 0.3048)
			(end -0.120396 0.2794)
			(stroke
				(width 0.1)
				(type default)
			)
			(layer "B.Fab")
		)
		(fp_line
			(start 0.12065 -0.305054)
			(end 0.12065 -0.2794)
			(stroke
				(width 0.1)
				(type default)
			)
			(layer "B.Fab")
		)
		(fp_line
			(start 0.12065 -0.2794)
			(end -0.12065 -0.2794)
			(stroke
				(width 0.1)
				(type default)
			)
			(layer "B.Fab")
		)
		(fp_line
			(start 0.12065 0.2794)
			(end 0.12065 0.3048)
			(stroke
				(width 0.1)
				(type default)
			)
			(layer "B.Fab")
		)
		(fp_line
			(start 0.12065 0.3048)
			(end 0.67945 0.3048)
			(stroke
				(width 0.1)
				(type default)
			)
			(layer "B.Fab")
		)
		(fp_line
			(start 0.67945 -0.305054)
			(end 0.12065 -0.305054)
			(stroke
				(width 0.1)
				(type default)
			)
			(layer "B.Fab")
		)
		(fp_line
			(start 0.67945 0.3048)
			(end 0.67945 -0.305054)
			(stroke
				(width 0.1)
				(type default)
			)
			(layer "B.Fab")
		)
		(pad "1" smd circle
			(at 0.40005 0 180)
			(size 0 0)
			(layers "B.Cu" "B.Mask" "B.Paste")
			(net "PD_CHF_CPU1_DIMM2_SAA")
		)
		(pad "2" smd circle
			(at -0.40005 0 180)
			(size 0 0)
			(layers "B.Cu" "B.Mask" "B.Paste")
			(net "GND")
		)
	)
	(footprint ""
		(layer "B.Cu")
		(at 311.84088 -52.288948)
		(property "Reference" "R4103"
			(at 0 0 0)
			(layer "B.SilkS")
			(hide yes)
			(effects
				(font
					(size 1.27 1.27)
				)
				(justify mirror)
			)
		)
		(property "Value" ""
			(at 0 0 0)
			(layer "B.Fab")
			(effects
				(font
					(size 1.27 1.27)
				)
				(justify mirror)
			)
		)
		(duplicate_pad_numbers_are_jumpers no)
		(fp_line
			(start -0.7874 -0.4064)
			(end -0.7874 0.4064)
			(stroke
				(width 0.1524)
				(type default)
			)
			(layer "B.SilkS")
		)
		(fp_line
			(start -0.7874 0.4064)
			(end 0.7874 0.4064)
			(stroke
				(width 0.1524)
				(type default)
			)
			(layer "B.SilkS")
		)
		(fp_line
			(start 0.7874 -0.4064)
			(end -0.7874 -0.4064)
			(stroke
				(width 0.1524)
				(type default)
			)
			(layer "B.SilkS")
		)
		(fp_line
			(start 0.7874 0.4064)
			(end 0.7874 -0.4064)
			(stroke
				(width 0.1524)
				(type default)
			)
			(layer "B.SilkS")
		)
		(fp_line
			(start -0.67945 -0.3048)
			(end -0.67945 0.3048)
			(stroke
				(width 0.1)
				(type default)
			)
			(layer "B.Fab")
		)
		(fp_line
			(start -0.67945 0.3048)
			(end -0.120396 0.3048)
			(stroke
				(width 0.1)
				(type default)
			)
			(layer "B.Fab")
		)
		(fp_line
			(start -0.12065 -0.3048)
			(end -0.67945 -0.3048)
			(stroke
				(width 0.1)
				(type default)
			)
			(layer "B.Fab")
		)
		(fp_line
			(start -0.12065 -0.2794)
			(end -0.12065 -0.3048)
			(stroke
				(width 0.1)
				(type default)
			)
			(layer "B.Fab")
		)
		(fp_line
			(start -0.120396 0.2794)
			(end 0.12065 0.2794)
			(stroke
				(width 0.1)
				(type default)
			)
			(layer "B.Fab")
		)
		(fp_line
			(start -0.120396 0.3048)
			(end -0.120396 0.2794)
			(stroke
				(width 0.1)
				(type default)
			)
			(layer "B.Fab")
		)
		(fp_line
			(start 0.12065 -0.305054)
			(end 0.12065 -0.2794)
			(stroke
				(width 0.1)
				(type default)
			)
			(layer "B.Fab")
		)
		(fp_line
			(start 0.12065 -0.2794)
			(end -0.12065 -0.2794)
			(stroke
				(width 0.1)
				(type default)
			)
			(layer "B.Fab")
		)
		(fp_line
			(start 0.12065 0.2794)
			(end 0.12065 0.3048)
			(stroke
				(width 0.1)
				(type default)
			)
			(layer "B.Fab")
		)
		(fp_line
			(start 0.12065 0.3048)
			(end 0.67945 0.3048)
			(stroke
				(width 0.1)
				(type default)
			)
			(layer "B.Fab")
		)
		(fp_line
			(start 0.67945 -0.305054)
			(end 0.12065 -0.305054)
			(stroke
				(width 0.1)
				(type default)
			)
			(layer "B.Fab")
		)
		(fp_line
			(start 0.67945 0.3048)
			(end 0.67945 -0.305054)
			(stroke
				(width 0.1)
				(type default)
			)
			(layer "B.Fab")
		)
		(pad "1" smd circle
			(at 0.40005 0 180)
			(size 0 0)
			(layers "B.Cu" "B.Mask" "B.Paste")
			(net "PD_GPP_M_17")
		)
		(pad "2" smd circle
			(at -0.40005 0 180)
			(size 0 0)
			(layers "B.Cu" "B.Mask" "B.Paste")
			(net "GND")
		)
	)
	(footprint ""
		(layer "B.Cu")
		(at 357.96093 -324.911466 -90)
		(property "Reference" "PC289_P0_3"
			(at 0 0 90)
			(layer "B.SilkS")
			(hide yes)
			(effects
				(font
					(size 1.27 1.27)
				)
				(justify mirror)
			)
		)
		(property "Value" ""
			(at 0 0 90)
			(layer "B.Fab")
			(effects
				(font
					(size 1.27 1.27)
				)
				(justify mirror)
			)
		)
		(duplicate_pad_numbers_are_jumpers no)
		(fp_line
			(start -1.524 0.762)
			(end 1.524 0.762)
			(stroke
				(width 0.1524)
				(type default)
			)
			(layer "B.SilkS")
		)
		(fp_line
			(start 1.524 0.762)
			(end 1.524 -0.762)
			(stroke
				(width 0.1524)
				(type default)
			)
			(layer "B.SilkS")
		)
		(fp_line
			(start -1.524 -0.762)
			(end -1.524 0.762)
			(stroke
				(width 0.1524)
				(type default)
			)
			(layer "B.SilkS")
		)
		(fp_line
			(start 1.524 -0.762)
			(end -1.524 -0.762)
			(stroke
				(width 0.1524)
				(type default)
			)
			(layer "B.SilkS")
		)
		(fp_line
			(start -1.1049 0.724916)
			(end -1.1049 -0.724916)
			(stroke
				(width 0.1)
				(type default)
			)
			(layer "B.Fab")
		)
		(fp_line
			(start 1.1049 0.724916)
			(end -1.1049 0.724916)
			(stroke
				(width 0.1)
				(type default)
			)
			(layer "B.Fab")
		)
		(fp_line
			(start -1.1049 -0.724916)
			(end 1.1049 -0.724916)
			(stroke
				(width 0.1)
				(type default)
			)
			(layer "B.Fab")
		)
		(fp_line
			(start 1.1049 -0.724916)
			(end 1.1049 0.724916)
			(stroke
				(width 0.1)
				(type default)
			)
			(layer "B.Fab")
		)
		(pad "1" smd rect
			(at 0.889 0 270)
			(size 1.016 1.27)
			(layers "B.Cu" "B.Mask" "B.Paste")
			(net "PVCCIN_CPU0")
		)
		(pad "2" smd rect
			(at -0.889 0 270)
			(size 1.016 1.27)
			(layers "B.Cu" "B.Mask" "B.Paste")
			(net "GND")
		)
	)
	(footprint ""
		(layer "B.Cu")
		(at 452.247 -81.031842 -90)
		(property "Reference" "D145"
			(at 1.205484 -1.580642 270)
			(unlocked yes)
			(layer "B.SilkS")
			(effects
				(font
					(size 0.7874 0.5842)
					(thickness 0.1524)
				)
				(justify left mirror)
			)
		)
		(property "Value" ""
			(at 0 0 90)
			(layer "B.Fab")
			(effects
				(font
					(size 1.27 1.27)
				)
				(justify mirror)
			)
		)
		(duplicate_pad_numbers_are_jumpers no)
		(fp_line
			(start -2.050796 0.700024)
			(end 2.050796 0.700024)
			(stroke
				(width 0.1524)
				(type default)
			)
			(layer "B.SilkS")
		)
		(fp_line
			(start 2.050796 0.700024)
			(end 2.050796 -0.700024)
			(stroke
				(width 0.1524)
				(type default)
			)
			(layer "B.SilkS")
		)
		(fp_line
			(start -2.343404 0.6985)
			(end -2.216404 0.6985)
			(stroke
				(width 0.1524)
				(type default)
			)
			(layer "B.SilkS")
		)
		(fp_line
			(start -2.229104 0.6985)
			(end -2.051304 0.6985)
			(stroke
				(width 0.1524)
				(type default)
			)
			(layer "B.SilkS")
		)
		(fp_line
			(start -2.051304 0.6985)
			(end -2.051304 0.635)
			(stroke
				(width 0.1524)
				(type default)
			)
			(layer "B.SilkS")
		)
		(fp_line
			(start -2.152904 0.635)
			(end -2.152904 -0.6985)
			(stroke
				(width 0.1524)
				(type default)
			)
			(layer "B.SilkS")
		)
		(fp_line
			(start -2.051304 0.635)
			(end -2.152904 0.635)
			(stroke
				(width 0.1524)
				(type default)
			)
			(layer "B.SilkS")
		)
		(fp_line
			(start 0.30607 0.500126)
			(end -0.193802 0)
			(stroke
				(width 0.1524)
				(type default)
			)
			(layer "B.SilkS")
		)
		(fp_line
			(start -0.193802 0)
			(end 0.30607 -0.500126)
			(stroke
				(width 0.1524)
				(type default)
			)
			(layer "B.SilkS")
		)
		(fp_line
			(start -0.293878 -0.500126)
			(end -0.293878 0.500126)
			(stroke
				(width 0.1524)
				(type default)
			)
			(layer "B.SilkS")
		)
		(fp_line
			(start 0.30607 -0.500126)
			(end 0.30607 0.500126)
			(stroke
				(width 0.1524)
				(type default)
			)
			(layer "B.SilkS")
		)
		(fp_line
			(start -2.064004 -0.6731)
			(end -2.064004 -0.6985)
			(stroke
				(width 0.1524)
				(type default)
			)
			(layer "B.SilkS")
		)
		(fp_line
			(start -2.343404 -0.6985)
			(end -2.343404 0.6985)
			(stroke
				(width 0.1524)
				(type default)
			)
			(layer "B.SilkS")
		)
		(fp_line
			(start -2.229104 -0.6985)
			(end -2.229104 0.6985)
			(stroke
				(width 0.1524)
				(type default)
			)
			(layer "B.SilkS")
		)
		(fp_line
			(start -2.152904 -0.6985)
			(end -2.343404 -0.6985)
			(stroke
				(width 0.1524)
				(type default)
			)
			(layer "B.SilkS")
		)
		(fp_line
			(start -2.064004 -0.6985)
			(end -2.229104 -0.6985)
			(stroke
				(width 0.1524)
				(type default)
			)
			(layer "B.SilkS")
		)
		(fp_line
			(start -2.050796 -0.700024)
			(end -2.050796 0.700024)
			(stroke
				(width 0.1524)
				(type default)
			)
			(layer "B.SilkS")
		)
		(fp_line
			(start 2.050796 -0.700024)
			(end -2.050796 -0.700024)
			(stroke
				(width 0.1524)
				(type default)
			)
			(layer "B.SilkS")
		)
		(fp_line
			(start -0.899922 0.700024)
			(end 0.899922 0.700024)
			(stroke
				(width 0.1)
				(type default)
			)
			(layer "B.Fab")
		)
		(fp_line
			(start 0.899922 0.700024)
			(end 0.899922 -0.700024)
			(stroke
				(width 0.1)
				(type default)
			)
			(layer "B.Fab")
		)
		(fp_line
			(start -0.899922 -0.700024)
			(end -0.899922 0.700024)
			(stroke
				(width 0.1)
				(type default)
			)
			(layer "B.Fab")
		)
		(fp_line
			(start 0.899922 -0.700024)
			(end -0.899922 -0.700024)
			(stroke
				(width 0.1)
				(type default)
			)
			(layer "B.Fab")
		)
		(fp_text user "+"
			(at 3.220466 -0.241046 180)
			(unlocked yes)
			(layer "B.SilkS")
			(effects
				(font
					(size 1.905 1.4224)
					(thickness 0.1524)
				)
				(justify left mirror)
			)
		)
		(fp_text user "-"
			(at -3.95732 -0.652526 90)
			(unlocked yes)
			(layer "B.SilkS")
			(effects
				(font
					(size 1.905 1.4224)
					(thickness 0.1524)
				)
				(justify left mirror)
			)
		)
		(fp_text user "+"
			(at 3.123946 0.762 180)
			(unlocked yes)
			(layer "B.Fab")
			(effects
				(font
					(size 1.905 1.4224)
					(thickness 0.1524)
				)
				(justify left mirror)
			)
		)
		(fp_text user "-"
			(at -3.880104 0.23495 90)
			(unlocked yes)
			(layer "B.Fab")
			(effects
				(font
					(size 1.905 1.4224)
					(thickness 0.1524)
				)
				(justify left mirror)
			)
		)
		(pad "1" smd rect
			(at 1.199896 0 180)
			(size 0.6604 1.3716)
			(layers "B.Cu" "B.Mask" "B.Paste")
			(net "MB0_P12V_STBY_PWRGD")
		)
		(pad "2" smd rect
			(at -1.199896 0)
			(size 0.6604 1.3716)
			(layers "B.Cu" "B.Mask" "B.Paste")
			(net "P3V3_AUX_EN")
		)
	)
	(footprint ""
		(layer "B.Cu")
		(at 184.976008 -398.651222)
		(property "Reference" "PR3931"
			(at 0 0 0)
			(layer "B.SilkS")
			(hide yes)
			(effects
				(font
					(size 1.27 1.27)
				)
				(justify mirror)
			)
		)
		(property "Value" ""
			(at 0 0 0)
			(layer "B.Fab")
			(effects
				(font
					(size 1.27 1.27)
				)
				(justify mirror)
			)
		)
		(duplicate_pad_numbers_are_jumpers no)
		(fp_line
			(start -0.7874 -0.4064)
			(end -0.7874 0.4064)
			(stroke
				(width 0.1524)
				(type default)
			)
			(layer "B.SilkS")
		)
		(fp_line
			(start -0.7874 0.4064)
			(end 0.7874 0.4064)
			(stroke
				(width 0.1524)
				(type default)
			)
			(layer "B.SilkS")
		)
		(fp_line
			(start 0.7874 -0.4064)
			(end -0.7874 -0.4064)
			(stroke
				(width 0.1524)
				(type default)
			)
			(layer "B.SilkS")
		)
		(fp_line
			(start 0.7874 0.4064)
			(end 0.7874 -0.4064)
			(stroke
				(width 0.1524)
				(type default)
			)
			(layer "B.SilkS")
		)
		(fp_line
			(start -0.67945 -0.3048)
			(end -0.67945 0.3048)
			(stroke
				(width 0.1)
				(type default)
			)
			(layer "B.Fab")
		)
		(fp_line
			(start -0.67945 0.3048)
			(end -0.120396 0.3048)
			(stroke
				(width 0.1)
				(type default)
			)
			(layer "B.Fab")
		)
		(fp_line
			(start -0.12065 -0.3048)
			(end -0.67945 -0.3048)
			(stroke
				(width 0.1)
				(type default)
			)
			(layer "B.Fab")
		)
		(fp_line
			(start -0.12065 -0.2794)
			(end -0.12065 -0.3048)
			(stroke
				(width 0.1)
				(type default)
			)
			(layer "B.Fab")
		)
		(fp_line
			(start -0.120396 0.2794)
			(end 0.12065 0.2794)
			(stroke
				(width 0.1)
				(type default)
			)
			(layer "B.Fab")
		)
		(fp_line
			(start -0.120396 0.3048)
			(end -0.120396 0.2794)
			(stroke
				(width 0.1)
				(type default)
			)
			(layer "B.Fab")
		)
		(fp_line
			(start 0.12065 -0.305054)
			(end 0.12065 -0.2794)
			(stroke
				(width 0.1)
				(type default)
			)
			(layer "B.Fab")
		)
		(fp_line
			(start 0.12065 -0.2794)
			(end -0.12065 -0.2794)
			(stroke
				(width 0.1)
				(type default)
			)
			(layer "B.Fab")
		)
		(fp_line
			(start 0.12065 0.2794)
			(end 0.12065 0.3048)
			(stroke
				(width 0.1)
				(type default)
			)
			(layer "B.Fab")
		)
		(fp_line
			(start 0.12065 0.3048)
			(end 0.67945 0.3048)
			(stroke
				(width 0.1)
				(type default)
			)
			(layer "B.Fab")
		)
		(fp_line
			(start 0.67945 -0.305054)
			(end 0.12065 -0.305054)
			(stroke
				(width 0.1)
				(type default)
			)
			(layer "B.Fab")
		)
		(fp_line
			(start 0.67945 0.3048)
			(end 0.67945 -0.305054)
			(stroke
				(width 0.1)
				(type default)
			)
			(layer "B.Fab")
		)
		(pad "1" smd circle
			(at 0.40005 0 180)
			(size 0 0)
			(layers "B.Cu" "B.Mask" "B.Paste")
			(net "P12V_AUX")
		)
		(pad "2" smd circle
			(at -0.40005 0 180)
			(size 0 0)
			(layers "B.Cu" "B.Mask" "B.Paste")
			(net "HSC_VOSEN")
		)
	)
	(footprint ""
		(layer "B.Cu")
		(at 155.792932 -238.728758)
		(property "Reference" "R4089"
			(at 0 0 0)
			(layer "B.SilkS")
			(hide yes)
			(effects
				(font
					(size 1.27 1.27)
				)
				(justify mirror)
			)
		)
		(property "Value" ""
			(at 0 0 0)
			(layer "B.Fab")
			(effects
				(font
					(size 1.27 1.27)
				)
				(justify mirror)
			)
		)
		(duplicate_pad_numbers_are_jumpers no)
		(fp_line
			(start -0.7874 -0.406146)
			(end -0.7874 0.406146)
			(stroke
				(width 0.1524)
				(type default)
			)
			(layer "B.SilkS")
		)
		(fp_line
			(start -0.7874 0.406146)
			(end 0.7874 0.406146)
			(stroke
				(width 0.1524)
				(type default)
			)
			(layer "B.SilkS")
		)
		(fp_line
			(start 0.7874 -0.406146)
			(end -0.7874 -0.406146)
			(stroke
				(width 0.1524)
				(type default)
			)
			(layer "B.SilkS")
		)
		(fp_line
			(start 0.7874 0.406146)
			(end 0.7874 -0.406146)
			(stroke
				(width 0.1524)
				(type default)
			)
			(layer "B.SilkS")
		)
		(fp_line
			(start -0.67945 -0.3048)
			(end -0.67945 0.3048)
			(stroke
				(width 0.1)
				(type default)
			)
			(layer "B.Fab")
		)
		(fp_line
			(start -0.67945 0.3048)
			(end -0.120396 0.3048)
			(stroke
				(width 0.1)
				(type default)
			)
			(layer "B.Fab")
		)
		(fp_line
			(start -0.12065 -0.2794)
			(end -0.120396 -0.3048)
			(stroke
				(width 0.1)
				(type default)
			)
			(layer "B.Fab")
		)
		(fp_line
			(start -0.120396 -0.3048)
			(end -0.67945 -0.3048)
			(stroke
				(width 0.1)
				(type default)
			)
			(layer "B.Fab")
		)
		(fp_line
			(start -0.120396 0.2794)
			(end 0.12065 0.2794)
			(stroke
				(width 0.1)
				(type default)
			)
			(layer "B.Fab")
		)
		(fp_line
			(start -0.120396 0.3048)
			(end -0.120396 0.2794)
			(stroke
				(width 0.1)
				(type default)
			)
			(layer "B.Fab")
		)
		(fp_line
			(start 0.120396 0.3048)
			(end 0.67945 0.3048)
			(stroke
				(width 0.1)
				(type default)
			)
			(layer "B.Fab")
		)
		(fp_line
			(start 0.12065 -0.305054)
			(end 0.12065 -0.2794)
			(stroke
				(width 0.1)
				(type default)
			)
			(layer "B.Fab")
		)
		(fp_line
			(start 0.12065 -0.2794)
			(end -0.12065 -0.2794)
			(stroke
				(width 0.1)
				(type default)
			)
			(layer "B.Fab")
		)
		(fp_line
			(start 0.12065 0.2794)
			(end 0.120396 0.3048)
			(stroke
				(width 0.1)
				(type default)
			)
			(layer "B.Fab")
		)
		(fp_line
			(start 0.67945 -0.305054)
			(end 0.12065 -0.305054)
			(stroke
				(width 0.1)
				(type default)
			)
			(layer "B.Fab")
		)
		(fp_line
			(start 0.67945 0.3048)
			(end 0.67945 -0.305054)
			(stroke
				(width 0.1)
				(type default)
			)
			(layer "B.Fab")
		)
		(pad "1" smd circle
			(at 0.40005 0 180)
			(size 0 0)
			(layers "B.Cu" "B.Mask" "B.Paste")
			(net "H_CPU0_PMSYNC_CPU1_R1")
		)
		(pad "2" smd circle
			(at -0.40005 0 180)
			(size 0 0)
			(layers "B.Cu" "B.Mask" "B.Paste")
			(net "H_CPU0_PMSYNC_CPU1")
		)
	)
)
